(kicad_pcb
	(version 20260206)
	(generator "pcbnew")
	(generator_version "10.0")
	(general
		(thickness 1.6)
		(legacy_teardrops no)
	)
	(paper "A4")
	(title_block
		(title "Bryce Canyon_F.DPB_16315-1-OCP.brd")
		(comment 1 "Bryce Canyon / footprints 390-397 of 2223")
	)
	(layers
		(0 "F.Cu" signal "TOP")
		(4 "In1.Cu" signal "L2GND")
		(6 "In2.Cu" signal "L3")
		(8 "In3.Cu" signal "L4GND")
		(10 "In4.Cu" signal "L5")
		(12 "In5.Cu" signal "L6VCC")
		(14 "In6.Cu" signal "L7VCC")
		(16 "In7.Cu" signal "L8")
		(18 "In8.Cu" signal "L9GND")
		(20 "In9.Cu" signal "L10")
		(22 "In10.Cu" signal "L11GND")
		(2 "B.Cu" signal "BOTTOM")
		(9 "F.Adhes" user "F.Adhesive")
		(11 "B.Adhes" user "B.Adhesive")
		(13 "F.Paste" user "Package Geometry/Pastemask Top")
		(15 "B.Paste" user "Package Geometry/Pastemask Bottom")
		(5 "F.SilkS" user "Ref Des/Silkscreen Top")
		(7 "B.SilkS" user "Ref Des/Silkscreen Bottom")
		(1 "F.Mask" user "Board Geometry/Soldermask Top")
		(3 "B.Mask" user "Board Geometry/Soldermask Bottom")
		(17 "Dwgs.User" user "User.Drawings")
		(19 "Cmts.User" user "User.Comments")
		(21 "Eco1.User" user "User.Eco1")
		(23 "Eco2.User" user "User.Eco2")
		(25 "Edge.Cuts" user "Board Geometry/Outline")
		(27 "Margin" user)
		(31 "F.CrtYd" user "Package Geometry/Place Bound Top")
		(29 "B.CrtYd" user "Package Geometry/Place Bound Bottom")
		(35 "F.Fab" user "Ref Des/Assembly Top")
		(33 "B.Fab" user "Ref Des/Assembly Bottom")
	)
	(footprint ""
		(layer "F.Cu")
		(at 456.048872 -189.380876 180)
		(property "Reference" "C333"
			(at 0 0 180)
			(layer "F.SilkS")
			(hide yes)
			(effects
				(font
					(size 1.27 1.27)
				)
			)
		)
		(property "Value" "SC1U25V3KX-GP"
			(at 0 -2.8194 180)
			(unlocked yes)
			(layer "F.Fab")
			(hide yes)
			(effects
				(font
					(size 1.016 1.016)
					(thickness 0.1524)
				)
			)
		)
		(property "Device Type" "C603H36"
			(at 0 -4.3434 180)
			(unlocked yes)
			(layer "F.Fab")
			(hide yes)
			(effects
				(font
					(size 1.016 1.016)
					(thickness 0.1524)
				)
			)
		)
		(duplicate_pad_numbers_are_jumpers no)
		(fp_line
			(start 0.508 0)
			(end -0.508 0)
			(stroke
				(width 0.2032)
				(type default)
			)
			(layer "F.SilkS")
		)
		(fp_rect
			(start -0.5842 1.3335)
			(end 0.5842 -1.3335)
			(stroke
				(width 0)
				(type default)
			)
			(fill no)
			(layer "F.CrtYd")
		)
		(fp_rect
			(start -0.5842 1.3335)
			(end 0.5842 -1.3335)
			(stroke
				(width 0)
				(type default)
			)
			(fill no)
			(layer "F.Fab")
		)
		(pad "1" smd custom
			(at 0 -0.762 180)
			(size 0.2159 0.2159)
			(layers "F.Cu" "F.Mask" "F.Paste")
			(net "P12V_HDD22")
			(options
				(clearance outline)
				(anchor circle)
			)
			(primitives
				(gr_poly
					(pts
						(arc
							(start -0.3302 -0.4318)
							(mid -0.402042 -0.402042)
							(end -0.4318 -0.3302)
						)
						(arc
							(start -0.4318 0.3302)
							(mid -0.402042 0.402042)
							(end -0.3302 0.4318)
						)
						(arc
							(start 0.3302 0.4318)
							(mid 0.402042 0.402042)
							(end 0.4318 0.3302)
						)
						(arc
							(start 0.4318 -0.3302)
							(mid 0.402042 -0.402042)
							(end 0.3302 -0.4318)
						)
					)
					(width 0)
					(fill yes)
				)
			)
		)
		(pad "2" smd custom
			(at 0 0.762 180)
			(size 0.2159 0.2159)
			(layers "F.Cu" "F.Mask" "F.Paste")
			(net "GND")
			(options
				(clearance outline)
				(anchor circle)
			)
			(primitives
				(gr_poly
					(pts
						(arc
							(start -0.3302 -0.4318)
							(mid -0.402042 -0.402042)
							(end -0.4318 -0.3302)
						)
						(arc
							(start -0.4318 0.3302)
							(mid -0.402042 0.402042)
							(end -0.3302 0.4318)
						)
						(arc
							(start 0.3302 0.4318)
							(mid 0.402042 0.402042)
							(end 0.4318 0.3302)
						)
						(arc
							(start 0.4318 -0.3302)
							(mid 0.402042 -0.402042)
							(end 0.3302 -0.4318)
						)
					)
					(width 0)
					(fill yes)
				)
			)
		)
	)
	(footprint ""
		(layer "F.Cu")
		(at 117.2718 -294.6908 90)
		(property "Reference" "R202"
			(at 0 0 90)
			(layer "F.SilkS")
			(hide yes)
			(effects
				(font
					(size 1.27 1.27)
				)
			)
		)
		(property "Value" "2R6F-GP"
			(at -0.0508 -4.8514 90)
			(unlocked yes)
			(layer "F.Fab")
			(hide yes)
			(effects
				(font
					(size 1.016 1.016)
					(thickness 0.1524)
				)
			)
		)
		(property "Device Type" "R1206H26"
			(at 0 -6.3754 90)
			(unlocked yes)
			(layer "F.Fab")
			(hide yes)
			(effects
				(font
					(size 1.016 1.016)
					(thickness 0.1524)
				)
			)
		)
		(duplicate_pad_numbers_are_jumpers no)
		(fp_line
			(start 1.016 -2.2352)
			(end 1.016 2.2352)
			(stroke
				(width 0.1524)
				(type default)
			)
			(layer "F.SilkS")
		)
		(fp_line
			(start -1.016 -2.2352)
			(end 1.016 -2.2352)
			(stroke
				(width 0.1524)
				(type default)
			)
			(layer "F.SilkS")
		)
		(fp_line
			(start 1.016 2.2352)
			(end -1.016 2.2352)
			(stroke
				(width 0.1524)
				(type default)
			)
			(layer "F.SilkS")
		)
		(fp_line
			(start -1.016 2.2352)
			(end -1.016 -2.2352)
			(stroke
				(width 0.1524)
				(type default)
			)
			(layer "F.SilkS")
		)
		(fp_rect
			(start -1.0922 2.3114)
			(end 1.0922 -2.3114)
			(stroke
				(width 0)
				(type default)
			)
			(fill no)
			(layer "F.CrtYd")
		)
		(fp_poly
			(pts
				(xy -1.0922 -2.3114) (xy 1.0922 -2.3114) (xy 1.0922 2.3114) (xy -1.0922 2.3114)
			)
			(stroke
				(width 0)
				(type default)
			)
			(fill no)
			(layer "F.Fab")
		)
		(pad "1" smd rect
			(at 0 -1.397 90)
			(size 1.651 1.27)
			(layers "F.Cu" "F.Mask" "F.Paste")
			(net "P12V_HDD3")
		)
		(pad "2" smd rect
			(at 0 1.397 90)
			(size 1.651 1.27)
			(layers "F.Cu" "F.Mask" "F.Paste")
			(net "12V_PRE_3")
		)
	)
	(footprint ""
		(layer "F.Cu")
		(at 329.819 -66.842894 180)
		(property "Reference" "C430"
			(at 0 0 180)
			(layer "F.SilkS")
			(hide yes)
			(effects
				(font
					(size 1.27 1.27)
				)
			)
		)
		(property "Value" "SC1U16V3KX-5GP"
			(at 0 -2.8194 180)
			(unlocked yes)
			(layer "F.Fab")
			(hide yes)
			(effects
				(font
					(size 1.016 1.016)
					(thickness 0.1524)
				)
			)
		)
		(property "Device Type" "C603H36"
			(at 0 -4.3434 180)
			(unlocked yes)
			(layer "F.Fab")
			(hide yes)
			(effects
				(font
					(size 1.016 1.016)
					(thickness 0.1524)
				)
			)
		)
		(duplicate_pad_numbers_are_jumpers no)
		(fp_line
			(start 0.508 0)
			(end -0.508 0)
			(stroke
				(width 0.2032)
				(type default)
			)
			(layer "F.SilkS")
		)
		(fp_rect
			(start -0.5842 1.3335)
			(end 0.5842 -1.3335)
			(stroke
				(width 0)
				(type default)
			)
			(fill no)
			(layer "F.CrtYd")
		)
		(fp_rect
			(start -0.5842 1.3335)
			(end 0.5842 -1.3335)
			(stroke
				(width 0)
				(type default)
			)
			(fill no)
			(layer "F.Fab")
		)
		(pad "1" smd custom
			(at 0 -0.762 180)
			(size 0.2159 0.2159)
			(layers "F.Cu" "F.Mask" "F.Paste")
			(net "P5V_HDD30")
			(options
				(clearance outline)
				(anchor circle)
			)
			(primitives
				(gr_poly
					(pts
						(arc
							(start -0.3302 -0.4318)
							(mid -0.402042 -0.402042)
							(end -0.4318 -0.3302)
						)
						(arc
							(start -0.4318 0.3302)
							(mid -0.402042 0.402042)
							(end -0.3302 0.4318)
						)
						(arc
							(start 0.3302 0.4318)
							(mid 0.402042 0.402042)
							(end 0.4318 0.3302)
						)
						(arc
							(start 0.4318 -0.3302)
							(mid 0.402042 -0.402042)
							(end 0.3302 -0.4318)
						)
					)
					(width 0)
					(fill yes)
				)
			)
		)
		(pad "2" smd custom
			(at 0 0.762 180)
			(size 0.2159 0.2159)
			(layers "F.Cu" "F.Mask" "F.Paste")
			(net "GND")
			(options
				(clearance outline)
				(anchor circle)
			)
			(primitives
				(gr_poly
					(pts
						(arc
							(start -0.3302 -0.4318)
							(mid -0.402042 -0.402042)
							(end -0.4318 -0.3302)
						)
						(arc
							(start -0.4318 0.3302)
							(mid -0.402042 0.402042)
							(end -0.3302 0.4318)
						)
						(arc
							(start 0.3302 0.4318)
							(mid 0.402042 0.402042)
							(end 0.4318 0.3302)
						)
						(arc
							(start 0.4318 -0.3302)
							(mid 0.402042 -0.402042)
							(end 0.3302 -0.4318)
						)
					)
					(width 0)
					(fill yes)
				)
			)
		)
	)
	(footprint ""
		(layer "F.Cu")
		(at 254.557276 -248.87936 180)
		(property "Reference" "R61"
			(at 0 0 180)
			(layer "F.SilkS")
			(hide yes)
			(effects
				(font
					(size 1.27 1.27)
				)
			)
		)
		(property "Value" "4K7R2F-GP"
			(at 0.064008 -3.993896 180)
			(unlocked yes)
			(layer "F.Fab")
			(hide yes)
			(effects
				(font
					(size 1.016 1.016)
					(thickness 0.1524)
				)
			)
		)
		(property "Device Type" "R402H16"
			(at 0.064008 -5.517896 180)
			(unlocked yes)
			(layer "F.Fab")
			(hide yes)
			(effects
				(font
					(size 1.016 1.016)
					(thickness 0.1524)
				)
			)
		)
		(duplicate_pad_numbers_are_jumpers no)
		(fp_line
			(start 0.508 -0.9398)
			(end -0.508 -0.9398)
			(stroke
				(width 0.1524)
				(type default)
			)
			(layer "F.SilkS")
		)
		(fp_line
			(start -0.508 -0.9398)
			(end -0.508 0.9398)
			(stroke
				(width 0.1524)
				(type default)
			)
			(layer "F.SilkS")
		)
		(fp_rect
			(start -0.508 0.9398)
			(end 0.508 -0.9398)
			(stroke
				(width 0)
				(type default)
			)
			(fill no)
			(layer "F.CrtYd")
		)
		(fp_rect
			(start -0.508 0.9398)
			(end 0.508 -0.9398)
			(stroke
				(width 0)
				(type default)
			)
			(fill no)
			(layer "F.Fab")
		)
		(pad "1" smd custom
			(at 0 -0.4445 180)
			(size 0.1397 0.1397)
			(layers "F.Cu" "F.Mask" "F.Paste")
			(net "P3V3_STBY_A")
			(options
				(clearance outline)
				(anchor circle)
			)
			(primitives
				(gr_poly
					(pts
						(arc
							(start -0.1778 -0.2794)
							(mid -0.249642 -0.249642)
							(end -0.2794 -0.1778)
						)
						(arc
							(start -0.2794 0.1778)
							(mid -0.249642 0.249642)
							(end -0.1778 0.2794)
						)
						(arc
							(start 0.1778 0.2794)
							(mid 0.249642 0.249642)
							(end 0.2794 0.1778)
						)
						(arc
							(start 0.2794 -0.1778)
							(mid 0.249642 -0.249642)
							(end 0.1778 -0.2794)
						)
					)
					(width 0)
					(fill yes)
				)
			)
		)
		(pad "2" smd custom
			(at 0 0.4445 180)
			(size 0.1397 0.1397)
			(layers "F.Cu" "F.Mask" "F.Paste")
			(net "IO_EXP6_A1")
			(options
				(clearance outline)
				(anchor circle)
			)
			(primitives
				(gr_poly
					(pts
						(arc
							(start -0.1778 -0.2794)
							(mid -0.249642 -0.249642)
							(end -0.2794 -0.1778)
						)
						(arc
							(start -0.2794 0.1778)
							(mid -0.249642 0.249642)
							(end -0.1778 0.2794)
						)
						(arc
							(start 0.1778 0.2794)
							(mid 0.249642 0.249642)
							(end 0.2794 0.1778)
						)
						(arc
							(start 0.2794 -0.1778)
							(mid 0.249642 -0.249642)
							(end 0.1778 -0.2794)
						)
					)
					(width 0)
					(fill yes)
				)
			)
		)
	)
	(footprint ""
		(layer "F.Cu")
		(at 133.852158 -130.271012 -90)
		(property "Reference" "R519"
			(at 0 0 270)
			(layer "F.SilkS")
			(hide yes)
			(effects
				(font
					(size 1.27 1.27)
				)
			)
		)
		(property "Value" "4K7R2J-2-GP"
			(at 0.064008 -3.993896 270)
			(unlocked yes)
			(layer "F.Fab")
			(hide yes)
			(effects
				(font
					(size 1.016 1.016)
					(thickness 0.1524)
				)
			)
		)
		(property "Device Type" "R402H16"
			(at 0.064008 -5.517896 270)
			(unlocked yes)
			(layer "F.Fab")
			(hide yes)
			(effects
				(font
					(size 1.016 1.016)
					(thickness 0.1524)
				)
			)
		)
		(duplicate_pad_numbers_are_jumpers no)
		(fp_line
			(start -0.508 -0.9398)
			(end -0.508 0.9398)
			(stroke
				(width 0.1524)
				(type default)
			)
			(layer "F.SilkS")
		)
		(fp_line
			(start 0.508 -0.9398)
			(end -0.508 -0.9398)
			(stroke
				(width 0.1524)
				(type default)
			)
			(layer "F.SilkS")
		)
		(fp_rect
			(start -0.508 0.9398)
			(end 0.508 -0.9398)
			(stroke
				(width 0)
				(type default)
			)
			(fill no)
			(layer "F.CrtYd")
		)
		(fp_rect
			(start -0.508 0.9398)
			(end 0.508 -0.9398)
			(stroke
				(width 0)
				(type default)
			)
			(fill no)
			(layer "F.Fab")
		)
		(pad "1" smd custom
			(at 0 -0.4445 270)
			(size 0.1397 0.1397)
			(layers "F.Cu" "F.Mask" "F.Paste")
			(net "DRIVE_A_16_FLT_LED")
			(options
				(clearance outline)
				(anchor circle)
			)
			(primitives
				(gr_poly
					(pts
						(arc
							(start -0.1778 -0.2794)
							(mid -0.249642 -0.249642)
							(end -0.2794 -0.1778)
						)
						(arc
							(start -0.2794 0.1778)
							(mid -0.249642 0.249642)
							(end -0.1778 0.2794)
						)
						(arc
							(start 0.1778 0.2794)
							(mid 0.249642 0.249642)
							(end 0.2794 0.1778)
						)
						(arc
							(start 0.2794 -0.1778)
							(mid 0.249642 -0.249642)
							(end 0.1778 -0.2794)
						)
					)
					(width 0)
					(fill yes)
				)
			)
		)
		(pad "2" smd custom
			(at 0 0.4445 270)
			(size 0.1397 0.1397)
			(layers "F.Cu" "F.Mask" "F.Paste")
			(net "GND")
			(options
				(clearance outline)
				(anchor circle)
			)
			(primitives
				(gr_poly
					(pts
						(arc
							(start -0.1778 -0.2794)
							(mid -0.249642 -0.249642)
							(end -0.2794 -0.1778)
						)
						(arc
							(start -0.2794 0.1778)
							(mid -0.249642 0.249642)
							(end -0.1778 0.2794)
						)
						(arc
							(start 0.1778 0.2794)
							(mid 0.249642 0.249642)
							(end 0.2794 0.1778)
						)
						(arc
							(start 0.2794 -0.1778)
							(mid 0.249642 -0.249642)
							(end 0.1778 -0.2794)
						)
					)
					(width 0)
					(fill yes)
				)
			)
		)
	)
	(footprint ""
		(layer "F.Cu")
		(at 259.969 -272.288)
		(property "Reference" "R104"
			(at 0 0 0)
			(layer "F.SilkS")
			(hide yes)
			(effects
				(font
					(size 1.27 1.27)
				)
			)
		)
		(property "Value" "4K7R2F-GP"
			(at 0.064008 -3.993896 0)
			(unlocked yes)
			(layer "F.Fab")
			(hide yes)
			(effects
				(font
					(size 1.016 1.016)
					(thickness 0.1524)
				)
			)
		)
		(property "Device Type" "R402H16"
			(at 0.064008 -5.517896 0)
			(unlocked yes)
			(layer "F.Fab")
			(hide yes)
			(effects
				(font
					(size 1.016 1.016)
					(thickness 0.1524)
				)
			)
		)
		(duplicate_pad_numbers_are_jumpers no)
		(fp_line
			(start -0.508 -0.9398)
			(end -0.508 0.9398)
			(stroke
				(width 0.1524)
				(type default)
			)
			(layer "F.SilkS")
		)
		(fp_line
			(start 0.508 -0.9398)
			(end -0.508 -0.9398)
			(stroke
				(width 0.1524)
				(type default)
			)
			(layer "F.SilkS")
		)
		(fp_rect
			(start -0.508 0.9398)
			(end 0.508 -0.9398)
			(stroke
				(width 0)
				(type default)
			)
			(fill no)
			(layer "F.CrtYd")
		)
		(fp_rect
			(start -0.508 0.9398)
			(end 0.508 -0.9398)
			(stroke
				(width 0)
				(type default)
			)
			(fill no)
			(layer "F.Fab")
		)
		(pad "1" smd custom
			(at 0 -0.4445)
			(size 0.1397 0.1397)
			(layers "F.Cu" "F.Mask" "F.Paste")
			(net "IO_EXP0_INT_N")
			(options
				(clearance outline)
				(anchor circle)
			)
			(primitives
				(gr_poly
					(pts
						(arc
							(start -0.1778 -0.2794)
							(mid -0.249642 -0.249642)
							(end -0.2794 -0.1778)
						)
						(arc
							(start -0.2794 0.1778)
							(mid -0.249642 0.249642)
							(end -0.1778 0.2794)
						)
						(arc
							(start 0.1778 0.2794)
							(mid 0.249642 0.249642)
							(end 0.2794 0.1778)
						)
						(arc
							(start 0.2794 -0.1778)
							(mid 0.249642 -0.249642)
							(end 0.1778 -0.2794)
						)
					)
					(width 0)
					(fill yes)
				)
			)
		)
		(pad "2" smd custom
			(at 0 0.4445)
			(size 0.1397 0.1397)
			(layers "F.Cu" "F.Mask" "F.Paste")
			(net "P3V3_STBY_A")
			(options
				(clearance outline)
				(anchor circle)
			)
			(primitives
				(gr_poly
					(pts
						(arc
							(start -0.1778 -0.2794)
							(mid -0.249642 -0.249642)
							(end -0.2794 -0.1778)
						)
						(arc
							(start -0.2794 0.1778)
							(mid -0.249642 0.249642)
							(end -0.1778 0.2794)
						)
						(arc
							(start 0.1778 0.2794)
							(mid 0.249642 0.249642)
							(end 0.2794 0.1778)
						)
						(arc
							(start 0.2794 -0.1778)
							(mid 0.249642 -0.249642)
							(end 0.1778 -0.2794)
						)
					)
					(width 0)
					(fill yes)
				)
			)
		)
	)
	(footprint ""
		(layer "F.Cu")
		(at 335.7626 -45.735494 180)
		(property "Reference" "R837"
			(at 0 0 180)
			(layer "F.SilkS")
			(hide yes)
			(effects
				(font
					(size 1.27 1.27)
				)
			)
		)
		(property "Value" "0R2J-2-GP"
			(at 0.064008 -3.993896 180)
			(unlocked yes)
			(layer "F.Fab")
			(hide yes)
			(effects
				(font
					(size 1.016 1.016)
					(thickness 0.1524)
				)
			)
		)
		(property "Device Type" "R402H16"
			(at 0.064008 -5.517896 180)
			(unlocked yes)
			(layer "F.Fab")
			(hide yes)
			(effects
				(font
					(size 1.016 1.016)
					(thickness 0.1524)
				)
			)
		)
		(duplicate_pad_numbers_are_jumpers no)
		(fp_line
			(start 0.508 -0.9398)
			(end -0.508 -0.9398)
			(stroke
				(width 0.1524)
				(type default)
			)
			(layer "F.SilkS")
		)
		(fp_line
			(start -0.508 -0.9398)
			(end -0.508 0.9398)
			(stroke
				(width 0.1524)
				(type default)
			)
			(layer "F.SilkS")
		)
		(fp_rect
			(start -0.508 0.9398)
			(end 0.508 -0.9398)
			(stroke
				(width 0)
				(type default)
			)
			(fill no)
			(layer "F.CrtYd")
		)
		(fp_rect
			(start -0.508 0.9398)
			(end 0.508 -0.9398)
			(stroke
				(width 0)
				(type default)
			)
			(fill no)
			(layer "F.Fab")
		)
		(pad "1" smd custom
			(at 0 -0.4445 180)
			(size 0.1397 0.1397)
			(layers "F.Cu" "F.Mask" "F.Paste")
			(net "SW_HDD_G30")
			(options
				(clearance outline)
				(anchor circle)
			)
			(primitives
				(gr_poly
					(pts
						(arc
							(start -0.1778 -0.2794)
							(mid -0.249642 -0.249642)
							(end -0.2794 -0.1778)
						)
						(arc
							(start -0.2794 0.1778)
							(mid -0.249642 0.249642)
							(end -0.1778 0.2794)
						)
						(arc
							(start 0.1778 0.2794)
							(mid 0.249642 0.249642)
							(end 0.2794 0.1778)
						)
						(arc
							(start 0.2794 -0.1778)
							(mid 0.249642 -0.249642)
							(end 0.1778 -0.2794)
						)
					)
					(width 0)
					(fill yes)
				)
			)
		)
		(pad "2" smd custom
			(at 0 0.4445 180)
			(size 0.1397 0.1397)
			(layers "F.Cu" "F.Mask" "F.Paste")
			(net "SW_HDD_R30")
			(options
				(clearance outline)
				(anchor circle)
			)
			(primitives
				(gr_poly
					(pts
						(arc
							(start -0.1778 -0.2794)
							(mid -0.249642 -0.249642)
							(end -0.2794 -0.1778)
						)
						(arc
							(start -0.2794 0.1778)
							(mid -0.249642 0.249642)
							(end -0.1778 0.2794)
						)
						(arc
							(start 0.1778 0.2794)
							(mid 0.249642 0.249642)
							(end 0.2794 0.1778)
						)
						(arc
							(start 0.2794 -0.1778)
							(mid 0.249642 -0.249642)
							(end 0.1778 -0.2794)
						)
					)
					(width 0)
					(fill yes)
				)
			)
		)
	)
	(footprint ""
		(layer "F.Cu")
		(at 54.295802 -150.67915)
		(property "Reference" "TP257"
			(at 0 0 0)
			(layer "F.SilkS")
			(hide yes)
			(effects
				(font
					(size 1.27 1.27)
				)
			)
		)
		(property "Value" "TPAD32-GP"
			(at -0.0508 -1.6764 0)
			(unlocked yes)
			(layer "F.Fab")
			(hide yes)
			(effects
				(font
					(size 1.016 1.016)
					(thickness 0.1524)
				)
			)
		)
		(property "Device Type" "TPAD32"
			(at -0.0508 -3.2004 0)
			(unlocked yes)
			(layer "F.Fab")
			(hide yes)
			(effects
				(font
					(size 1.016 1.016)
					(thickness 0.1524)
				)
			)
		)
		(duplicate_pad_numbers_are_jumpers no)
		(fp_poly
			(pts
				(arc
					(start 0.4064 0)
					(mid -0.4064 0)
					(end 0.4064 0)
				)
			)
			(stroke
				(width 0)
				(type default)
			)
			(fill no)
			(layer "F.CrtYd")
		)
		(fp_poly
			(pts
				(arc
					(start 0.7112 0)
					(mid -0.7112 0)
					(end 0.7112 0)
				)
			)
			(stroke
				(width 0)
				(type default)
			)
			(fill no)
			(layer "F.Fab")
		)
		(pad "1" smd circle
			(at 0 0)
			(size 0.8128 0.8128)
			(layers "F.Cu" "F.Mask" "F.Paste")
			(net "P5V_A_2_PGOOD")
		)
	)
)
